(kicad_pcb
	(version 20260206)
	(generator "pcbnew")
	(generator_version "10.0")
	(general
		(thickness 1.6)
		(legacy_teardrops no)
	)
	(paper "A4")
	(title_block
		(title "01162023_DA0F0TEBIF0_F0T_Expander_BD_F_brd_V02_OCP.brd")
		(comment 1 "Grand Teton / footprints 6585-6591 of 9728")
	)
	(layers
		(0 "F.Cu" signal "TOP")
		(4 "In1.Cu" signal "GND")
		(6 "In2.Cu" signal "VCC")
		(8 "In3.Cu" signal "VCC1")
		(10 "In4.Cu" signal "GND1")
		(12 "In5.Cu" signal "IN1")
		(14 "In6.Cu" signal "GND2")
		(16 "In7.Cu" signal "IN2")
		(18 "In8.Cu" signal "GND3")
		(20 "In9.Cu" signal "IN3")
		(22 "In10.Cu" signal "GND4")
		(24 "In11.Cu" signal "IN4")
		(26 "In12.Cu" signal "GND5")
		(28 "In13.Cu" signal "IN5")
		(30 "In14.Cu" signal "GND6")
		(32 "In15.Cu" signal "IN6")
		(34 "In16.Cu" signal "GND7")
		(2 "B.Cu" signal "BOTTOM")
		(9 "F.Adhes" user "F.Adhesive")
		(11 "B.Adhes" user "B.Adhesive")
		(13 "F.Paste" user "Package Geometry/Pastemask Top")
		(15 "B.Paste" user "Package Geometry/Pastemask Bottom")
		(5 "F.SilkS" user "Ref Des/Silkscreen Top")
		(7 "B.SilkS" user "Ref Des/Silkscreen Bottom")
		(1 "F.Mask" user "Board Geometry/Soldermask Top")
		(3 "B.Mask" user "Board Geometry/Soldermask Bottom")
		(17 "Dwgs.User" user "User.Drawings")
		(19 "Cmts.User" user "User.Comments")
		(21 "Eco1.User" user "User.Eco1")
		(23 "Eco2.User" user "User.Eco2")
		(25 "Edge.Cuts" user "Board Geometry/Outline")
		(27 "Margin" user)
		(31 "F.CrtYd" user "Package Geometry/Place Bound Top")
		(29 "B.CrtYd" user "Package Geometry/Place Bound Bottom")
		(35 "F.Fab" user "Ref Des/Assembly Top")
		(33 "B.Fab" user "Ref Des/Assembly Bottom")
	)
	(footprint ""
		(layer "F.Cu")
		(at 113.21923 -159.27324 -90)
		(property "Reference" "PR62"
			(at 0 0 270)
			(layer "F.SilkS")
			(hide yes)
			(effects
				(font
					(size 1.27 1.27)
				)
			)
		)
		(property "Value" ""
			(at 0 0 270)
			(layer "F.Fab")
			(effects
				(font
					(size 1.27 1.27)
				)
			)
		)
		(duplicate_pad_numbers_are_jumpers no)
		(fp_line
			(start -0.7874 0.4064)
			(end -0.7874 -0.4064)
			(stroke
				(width 0.1524)
				(type default)
			)
			(layer "F.SilkS")
		)
		(fp_line
			(start 0.7874 0.4064)
			(end -0.7874 0.4064)
			(stroke
				(width 0.1524)
				(type default)
			)
			(layer "F.SilkS")
		)
		(fp_line
			(start -0.7874 -0.4064)
			(end 0.7874 -0.4064)
			(stroke
				(width 0.1524)
				(type default)
			)
			(layer "F.SilkS")
		)
		(fp_line
			(start 0.7874 -0.4064)
			(end 0.7874 0.4064)
			(stroke
				(width 0.1524)
				(type default)
			)
			(layer "F.SilkS")
		)
		(fp_line
			(start -0.67945 0.3048)
			(end -0.67945 -0.305054)
			(stroke
				(width 0.1)
				(type default)
			)
			(layer "F.Fab")
		)
		(fp_line
			(start -0.12065 0.3048)
			(end -0.67945 0.3048)
			(stroke
				(width 0.1)
				(type default)
			)
			(layer "F.Fab")
		)
		(fp_line
			(start 0.120396 0.3048)
			(end 0.120396 0.2794)
			(stroke
				(width 0.1)
				(type default)
			)
			(layer "F.Fab")
		)
		(fp_line
			(start 0.67945 0.3048)
			(end 0.120396 0.3048)
			(stroke
				(width 0.1)
				(type default)
			)
			(layer "F.Fab")
		)
		(fp_line
			(start -0.12065 0.2794)
			(end -0.12065 0.3048)
			(stroke
				(width 0.1)
				(type default)
			)
			(layer "F.Fab")
		)
		(fp_line
			(start 0.120396 0.2794)
			(end -0.12065 0.2794)
			(stroke
				(width 0.1)
				(type default)
			)
			(layer "F.Fab")
		)
		(fp_line
			(start -0.12065 -0.2794)
			(end 0.12065 -0.2794)
			(stroke
				(width 0.1)
				(type default)
			)
			(layer "F.Fab")
		)
		(fp_line
			(start 0.12065 -0.2794)
			(end 0.12065 -0.3048)
			(stroke
				(width 0.1)
				(type default)
			)
			(layer "F.Fab")
		)
		(fp_line
			(start 0.12065 -0.3048)
			(end 0.67945 -0.3048)
			(stroke
				(width 0.1)
				(type default)
			)
			(layer "F.Fab")
		)
		(fp_line
			(start 0.67945 -0.3048)
			(end 0.67945 0.3048)
			(stroke
				(width 0.1)
				(type default)
			)
			(layer "F.Fab")
		)
		(fp_line
			(start -0.67945 -0.305054)
			(end -0.12065 -0.305054)
			(stroke
				(width 0.1)
				(type default)
			)
			(layer "F.Fab")
		)
		(fp_line
			(start -0.12065 -0.305054)
			(end -0.12065 -0.2794)
			(stroke
				(width 0.1)
				(type default)
			)
			(layer "F.Fab")
		)
		(pad "1" smd circle
			(at -0.40005 0 270)
			(size 0 0)
			(layers "F.Cu" "F.Mask" "F.Paste")
			(net "P3V3_AUX_CS")
		)
		(pad "2" smd circle
			(at 0.40005 0 270)
			(size 0 0)
			(layers "F.Cu" "F.Mask" "F.Paste")
			(net "GND")
		)
	)
	(footprint ""
		(layer "F.Cu")
		(at 362.064808 -162.003994 90)
		(property "Reference" "PC833"
			(at 0 0 90)
			(layer "F.SilkS")
			(hide yes)
			(effects
				(font
					(size 1.27 1.27)
				)
			)
		)
		(property "Value" ""
			(at 0 0 90)
			(layer "F.Fab")
			(effects
				(font
					(size 1.27 1.27)
				)
			)
		)
		(duplicate_pad_numbers_are_jumpers no)
		(fp_line
			(start 0.7874 -0.4064)
			(end 0.7874 0.4064)
			(stroke
				(width 0.1524)
				(type default)
			)
			(layer "F.SilkS")
		)
		(fp_line
			(start -0.7874 -0.4064)
			(end 0.7874 -0.4064)
			(stroke
				(width 0.1524)
				(type default)
			)
			(layer "F.SilkS")
		)
		(fp_line
			(start 0.7874 0.4064)
			(end -0.7874 0.4064)
			(stroke
				(width 0.1524)
				(type default)
			)
			(layer "F.SilkS")
		)
		(fp_line
			(start -0.7874 0.4064)
			(end -0.7874 -0.4064)
			(stroke
				(width 0.1524)
				(type default)
			)
			(layer "F.SilkS")
		)
		(fp_line
			(start -0.12065 -0.305054)
			(end -0.12065 -0.2794)
			(stroke
				(width 0.1)
				(type default)
			)
			(layer "F.Fab")
		)
		(fp_line
			(start -0.67945 -0.305054)
			(end -0.12065 -0.305054)
			(stroke
				(width 0.1)
				(type default)
			)
			(layer "F.Fab")
		)
		(fp_line
			(start 0.67945 -0.3048)
			(end 0.67945 0.3048)
			(stroke
				(width 0.1)
				(type default)
			)
			(layer "F.Fab")
		)
		(fp_line
			(start 0.12065 -0.3048)
			(end 0.67945 -0.3048)
			(stroke
				(width 0.1)
				(type default)
			)
			(layer "F.Fab")
		)
		(fp_line
			(start 0.12065 -0.2794)
			(end 0.12065 -0.3048)
			(stroke
				(width 0.1)
				(type default)
			)
			(layer "F.Fab")
		)
		(fp_line
			(start -0.12065 -0.2794)
			(end 0.12065 -0.2794)
			(stroke
				(width 0.1)
				(type default)
			)
			(layer "F.Fab")
		)
		(fp_line
			(start 0.120396 0.2794)
			(end -0.12065 0.2794)
			(stroke
				(width 0.1)
				(type default)
			)
			(layer "F.Fab")
		)
		(fp_line
			(start -0.12065 0.2794)
			(end -0.12065 0.3048)
			(stroke
				(width 0.1)
				(type default)
			)
			(layer "F.Fab")
		)
		(fp_line
			(start 0.67945 0.3048)
			(end 0.120396 0.3048)
			(stroke
				(width 0.1)
				(type default)
			)
			(layer "F.Fab")
		)
		(fp_line
			(start 0.120396 0.3048)
			(end 0.120396 0.2794)
			(stroke
				(width 0.1)
				(type default)
			)
			(layer "F.Fab")
		)
		(fp_line
			(start -0.12065 0.3048)
			(end -0.67945 0.3048)
			(stroke
				(width 0.1)
				(type default)
			)
			(layer "F.Fab")
		)
		(fp_line
			(start -0.67945 0.3048)
			(end -0.67945 -0.305054)
			(stroke
				(width 0.1)
				(type default)
			)
			(layer "F.Fab")
		)
		(pad "1" smd circle
			(at -0.40005 0 90)
			(size 0 0)
			(layers "F.Cu" "F.Mask" "F.Paste")
			(net "P12V_NIC6_CO_TIMER")
		)
		(pad "2" smd circle
			(at 0.40005 0 90)
			(size 0 0)
			(layers "F.Cu" "F.Mask" "F.Paste")
			(net "GND")
		)
	)
	(footprint ""
		(layer "F.Cu")
		(at 177.295048 -59.577986 90)
		(property "Reference" "PC531"
			(at 0 0 90)
			(layer "F.SilkS")
			(hide yes)
			(effects
				(font
					(size 1.27 1.27)
				)
			)
		)
		(property "Value" ""
			(at 0 0 90)
			(layer "F.Fab")
			(effects
				(font
					(size 1.27 1.27)
				)
			)
		)
		(duplicate_pad_numbers_are_jumpers no)
		(fp_line
			(start 0.7874 -0.4064)
			(end 0.7874 0.4064)
			(stroke
				(width 0.1524)
				(type default)
			)
			(layer "F.SilkS")
		)
		(fp_line
			(start -0.7874 -0.4064)
			(end 0.7874 -0.4064)
			(stroke
				(width 0.1524)
				(type default)
			)
			(layer "F.SilkS")
		)
		(fp_line
			(start 0.7874 0.4064)
			(end -0.7874 0.4064)
			(stroke
				(width 0.1524)
				(type default)
			)
			(layer "F.SilkS")
		)
		(fp_line
			(start -0.7874 0.4064)
			(end -0.7874 -0.4064)
			(stroke
				(width 0.1524)
				(type default)
			)
			(layer "F.SilkS")
		)
		(fp_line
			(start -0.12065 -0.305054)
			(end -0.12065 -0.2794)
			(stroke
				(width 0.1)
				(type default)
			)
			(layer "F.Fab")
		)
		(fp_line
			(start -0.67945 -0.305054)
			(end -0.12065 -0.305054)
			(stroke
				(width 0.1)
				(type default)
			)
			(layer "F.Fab")
		)
		(fp_line
			(start 0.67945 -0.3048)
			(end 0.67945 0.3048)
			(stroke
				(width 0.1)
				(type default)
			)
			(layer "F.Fab")
		)
		(fp_line
			(start 0.12065 -0.3048)
			(end 0.67945 -0.3048)
			(stroke
				(width 0.1)
				(type default)
			)
			(layer "F.Fab")
		)
		(fp_line
			(start 0.12065 -0.2794)
			(end 0.12065 -0.3048)
			(stroke
				(width 0.1)
				(type default)
			)
			(layer "F.Fab")
		)
		(fp_line
			(start -0.12065 -0.2794)
			(end 0.12065 -0.2794)
			(stroke
				(width 0.1)
				(type default)
			)
			(layer "F.Fab")
		)
		(fp_line
			(start 0.120396 0.2794)
			(end -0.12065 0.2794)
			(stroke
				(width 0.1)
				(type default)
			)
			(layer "F.Fab")
		)
		(fp_line
			(start -0.12065 0.2794)
			(end -0.12065 0.3048)
			(stroke
				(width 0.1)
				(type default)
			)
			(layer "F.Fab")
		)
		(fp_line
			(start 0.67945 0.3048)
			(end 0.120396 0.3048)
			(stroke
				(width 0.1)
				(type default)
			)
			(layer "F.Fab")
		)
		(fp_line
			(start 0.120396 0.3048)
			(end 0.120396 0.2794)
			(stroke
				(width 0.1)
				(type default)
			)
			(layer "F.Fab")
		)
		(fp_line
			(start -0.12065 0.3048)
			(end -0.67945 0.3048)
			(stroke
				(width 0.1)
				(type default)
			)
			(layer "F.Fab")
		)
		(fp_line
			(start -0.67945 0.3048)
			(end -0.67945 -0.305054)
			(stroke
				(width 0.1)
				(type default)
			)
			(layer "F.Fab")
		)
		(pad "1" smd circle
			(at -0.40005 0 90)
			(size 0 0)
			(layers "F.Cu" "F.Mask" "F.Paste")
			(net "P3V3_SSD6_SS")
		)
		(pad "2" smd circle
			(at 0.40005 0 90)
			(size 0 0)
			(layers "F.Cu" "F.Mask" "F.Paste")
			(net "GND")
		)
	)
	(footprint ""
		(layer "F.Cu")
		(at 487.0577 -548.246554 180)
		(property "Reference" "SCREW_SSD3_1"
			(at -5.207 -1.402334 0)
			(unlocked yes)
			(layer "B.SilkS")
			(effects
				(font
					(size 0.7874 0.5842)
					(thickness 0.1524)
				)
				(justify mirror)
			)
		)
		(property "Value" ""
			(at 0 0 180)
			(layer "F.Fab")
			(effects
				(font
					(size 1.27 1.27)
				)
			)
		)
		(duplicate_pad_numbers_are_jumpers no)
		(pad "1" thru_hole circle
			(at 0 0 180)
			(size 0.4572 0.4572)
			(drill 0.2032)
			(layers "*.Cu" "*.Mask")
			(remove_unused_layers no)
			(net "Net_9138")
			(clearance 0.127)
			(thermal_gap 0.127)
			(padstack
				(mode front_inner_back)
				(layer "Inner"
					(shape circle)
					(size 0.4572 0.4572)
					(clearance 0.127)
				)
				(layer "B.Cu"
					(shape circle)
					(size 0.508 0.508)
					(clearance 0.1016)
				)
			)
		)
	)
	(footprint ""
		(layer "F.Cu")
		(at 37.004752 -140.85697 180)
		(property "Reference" "R33"
			(at 0 0 180)
			(layer "F.SilkS")
			(hide yes)
			(effects
				(font
					(size 1.27 1.27)
				)
			)
		)
		(property "Value" ""
			(at 0 0 180)
			(layer "F.Fab")
			(effects
				(font
					(size 1.27 1.27)
				)
			)
		)
		(duplicate_pad_numbers_are_jumpers no)
		(fp_line
			(start 0.7874 0.4064)
			(end -0.7874 0.4064)
			(stroke
				(width 0.1524)
				(type default)
			)
			(layer "F.SilkS")
		)
		(fp_line
			(start 0.7874 -0.4064)
			(end 0.7874 0.4064)
			(stroke
				(width 0.1524)
				(type default)
			)
			(layer "F.SilkS")
		)
		(fp_line
			(start -0.7874 0.4064)
			(end -0.7874 -0.4064)
			(stroke
				(width 0.1524)
				(type default)
			)
			(layer "F.SilkS")
		)
		(fp_line
			(start -0.7874 -0.4064)
			(end 0.7874 -0.4064)
			(stroke
				(width 0.1524)
				(type default)
			)
			(layer "F.SilkS")
		)
		(fp_line
			(start 0.67945 0.3048)
			(end 0.120396 0.3048)
			(stroke
				(width 0.1)
				(type default)
			)
			(layer "F.Fab")
		)
		(fp_line
			(start 0.67945 -0.3048)
			(end 0.67945 0.3048)
			(stroke
				(width 0.1)
				(type default)
			)
			(layer "F.Fab")
		)
		(fp_line
			(start 0.12065 -0.2794)
			(end 0.12065 -0.3048)
			(stroke
				(width 0.1)
				(type default)
			)
			(layer "F.Fab")
		)
		(fp_line
			(start 0.12065 -0.3048)
			(end 0.67945 -0.3048)
			(stroke
				(width 0.1)
				(type default)
			)
			(layer "F.Fab")
		)
		(fp_line
			(start 0.120396 0.3048)
			(end 0.120396 0.2794)
			(stroke
				(width 0.1)
				(type default)
			)
			(layer "F.Fab")
		)
		(fp_line
			(start 0.120396 0.2794)
			(end -0.12065 0.2794)
			(stroke
				(width 0.1)
				(type default)
			)
			(layer "F.Fab")
		)
		(fp_line
			(start -0.12065 0.3048)
			(end -0.67945 0.3048)
			(stroke
				(width 0.1)
				(type default)
			)
			(layer "F.Fab")
		)
		(fp_line
			(start -0.12065 0.2794)
			(end -0.12065 0.3048)
			(stroke
				(width 0.1)
				(type default)
			)
			(layer "F.Fab")
		)
		(fp_line
			(start -0.12065 -0.2794)
			(end 0.12065 -0.2794)
			(stroke
				(width 0.1)
				(type default)
			)
			(layer "F.Fab")
		)
		(fp_line
			(start -0.12065 -0.305054)
			(end -0.12065 -0.2794)
			(stroke
				(width 0.1)
				(type default)
			)
			(layer "F.Fab")
		)
		(fp_line
			(start -0.67945 0.3048)
			(end -0.67945 -0.305054)
			(stroke
				(width 0.1)
				(type default)
			)
			(layer "F.Fab")
		)
		(fp_line
			(start -0.67945 -0.305054)
			(end -0.12065 -0.305054)
			(stroke
				(width 0.1)
				(type default)
			)
			(layer "F.Fab")
		)
		(pad "1" smd circle
			(at -0.40005 0 180)
			(size 0 0)
			(layers "F.Cu" "F.Mask" "F.Paste")
			(net "NIC0_BIF2_N")
		)
		(pad "2" smd circle
			(at 0.40005 0 180)
			(size 0 0)
			(layers "F.Cu" "F.Mask" "F.Paste")
			(net "P3V3_AUX")
		)
	)
	(footprint ""
		(layer "F.Cu")
		(at 166.961058 -169.23385 180)
		(property "Reference" "C886"
			(at 0 0 180)
			(layer "F.SilkS")
			(hide yes)
			(effects
				(font
					(size 1.27 1.27)
				)
			)
		)
		(property "Value" ""
			(at 0 0 180)
			(layer "F.Fab")
			(effects
				(font
					(size 1.27 1.27)
				)
			)
		)
		(duplicate_pad_numbers_are_jumpers no)
		(fp_line
			(start 0.7874 0.4064)
			(end -0.7874 0.4064)
			(stroke
				(width 0.1524)
				(type default)
			)
			(layer "F.SilkS")
		)
		(fp_line
			(start 0.7874 -0.4064)
			(end 0.7874 0.4064)
			(stroke
				(width 0.1524)
				(type default)
			)
			(layer "F.SilkS")
		)
		(fp_line
			(start -0.7874 0.4064)
			(end -0.7874 -0.4064)
			(stroke
				(width 0.1524)
				(type default)
			)
			(layer "F.SilkS")
		)
		(fp_line
			(start -0.7874 -0.4064)
			(end 0.7874 -0.4064)
			(stroke
				(width 0.1524)
				(type default)
			)
			(layer "F.SilkS")
		)
		(fp_line
			(start 0.67945 0.3048)
			(end 0.120396 0.3048)
			(stroke
				(width 0.1)
				(type default)
			)
			(layer "F.Fab")
		)
		(fp_line
			(start 0.67945 -0.3048)
			(end 0.67945 0.3048)
			(stroke
				(width 0.1)
				(type default)
			)
			(layer "F.Fab")
		)
		(fp_line
			(start 0.12065 -0.2794)
			(end 0.12065 -0.3048)
			(stroke
				(width 0.1)
				(type default)
			)
			(layer "F.Fab")
		)
		(fp_line
			(start 0.12065 -0.3048)
			(end 0.67945 -0.3048)
			(stroke
				(width 0.1)
				(type default)
			)
			(layer "F.Fab")
		)
		(fp_line
			(start 0.120396 0.3048)
			(end 0.120396 0.2794)
			(stroke
				(width 0.1)
				(type default)
			)
			(layer "F.Fab")
		)
		(fp_line
			(start 0.120396 0.2794)
			(end -0.12065 0.2794)
			(stroke
				(width 0.1)
				(type default)
			)
			(layer "F.Fab")
		)
		(fp_line
			(start -0.12065 0.3048)
			(end -0.67945 0.3048)
			(stroke
				(width 0.1)
				(type default)
			)
			(layer "F.Fab")
		)
		(fp_line
			(start -0.12065 0.2794)
			(end -0.12065 0.3048)
			(stroke
				(width 0.1)
				(type default)
			)
			(layer "F.Fab")
		)
		(fp_line
			(start -0.12065 -0.2794)
			(end 0.12065 -0.2794)
			(stroke
				(width 0.1)
				(type default)
			)
			(layer "F.Fab")
		)
		(fp_line
			(start -0.12065 -0.305054)
			(end -0.12065 -0.2794)
			(stroke
				(width 0.1)
				(type default)
			)
			(layer "F.Fab")
		)
		(fp_line
			(start -0.67945 0.3048)
			(end -0.67945 -0.305054)
			(stroke
				(width 0.1)
				(type default)
			)
			(layer "F.Fab")
		)
		(fp_line
			(start -0.67945 -0.305054)
			(end -0.12065 -0.305054)
			(stroke
				(width 0.1)
				(type default)
			)
			(layer "F.Fab")
		)
		(pad "1" smd circle
			(at -0.40005 0 180)
			(size 0 0)
			(layers "F.Cu" "F.Mask" "F.Paste")
			(net "P3V3_AUX")
		)
		(pad "2" smd circle
			(at 0.40005 0 180)
			(size 0 0)
			(layers "F.Cu" "F.Mask" "F.Paste")
			(net "GND")
		)
	)
	(footprint ""
		(layer "F.Cu")
		(at 238.124746 -116.698268)
		(property "Reference" "PC637"
			(at 0 0 0)
			(layer "F.SilkS")
			(hide yes)
			(effects
				(font
					(size 1.27 1.27)
				)
			)
		)
		(property "Value" ""
			(at 0 0 0)
			(layer "F.Fab")
			(effects
				(font
					(size 1.27 1.27)
				)
			)
		)
		(duplicate_pad_numbers_are_jumpers no)
		(fp_line
			(start -0.7874 -0.4064)
			(end 0.7874 -0.4064)
			(stroke
				(width 0.1524)
				(type default)
			)
			(layer "F.SilkS")
		)
		(fp_line
			(start -0.7874 0.4064)
			(end -0.7874 -0.4064)
			(stroke
				(width 0.1524)
				(type default)
			)
			(layer "F.SilkS")
		)
		(fp_line
			(start 0.7874 -0.4064)
			(end 0.7874 0.4064)
			(stroke
				(width 0.1524)
				(type default)
			)
			(layer "F.SilkS")
		)
		(fp_line
			(start 0.7874 0.4064)
			(end -0.7874 0.4064)
			(stroke
				(width 0.1524)
				(type default)
			)
			(layer "F.SilkS")
		)
		(fp_line
			(start -0.67945 -0.305054)
			(end -0.12065 -0.305054)
			(stroke
				(width 0.1)
				(type default)
			)
			(layer "F.Fab")
		)
		(fp_line
			(start -0.67945 0.3048)
			(end -0.67945 -0.305054)
			(stroke
				(width 0.1)
				(type default)
			)
			(layer "F.Fab")
		)
		(fp_line
			(start -0.12065 -0.305054)
			(end -0.12065 -0.2794)
			(stroke
				(width 0.1)
				(type default)
			)
			(layer "F.Fab")
		)
		(fp_line
			(start -0.12065 -0.2794)
			(end 0.12065 -0.2794)
			(stroke
				(width 0.1)
				(type default)
			)
			(layer "F.Fab")
		)
		(fp_line
			(start -0.12065 0.2794)
			(end -0.12065 0.3048)
			(stroke
				(width 0.1)
				(type default)
			)
			(layer "F.Fab")
		)
		(fp_line
			(start -0.12065 0.3048)
			(end -0.67945 0.3048)
			(stroke
				(width 0.1)
				(type default)
			)
			(layer "F.Fab")
		)
		(fp_line
			(start 0.120396 0.2794)
			(end -0.12065 0.2794)
			(stroke
				(width 0.1)
				(type default)
			)
			(layer "F.Fab")
		)
		(fp_line
			(start 0.120396 0.3048)
			(end 0.120396 0.2794)
			(stroke
				(width 0.1)
				(type default)
			)
			(layer "F.Fab")
		)
		(fp_line
			(start 0.12065 -0.3048)
			(end 0.67945 -0.3048)
			(stroke
				(width 0.1)
				(type default)
			)
			(layer "F.Fab")
		)
		(fp_line
			(start 0.12065 -0.2794)
			(end 0.12065 -0.3048)
			(stroke
				(width 0.1)
				(type default)
			)
			(layer "F.Fab")
		)
		(fp_line
			(start 0.67945 -0.3048)
			(end 0.67945 0.3048)
			(stroke
				(width 0.1)
				(type default)
			)
			(layer "F.Fab")
		)
		(fp_line
			(start 0.67945 0.3048)
			(end 0.120396 0.3048)
			(stroke
				(width 0.1)
				(type default)
			)
			(layer "F.Fab")
		)
		(pad "1" smd circle
			(at -0.40005 0)
			(size 0 0)
			(layers "F.Cu" "F.Mask" "F.Paste")
			(net "P12V_NIC3_CO_ISET_R")
		)
		(pad "2" smd circle
			(at 0.40005 0)
			(size 0 0)
			(layers "F.Cu" "F.Mask" "F.Paste")
			(net "GND")
		)
	)
)
